# T6G (Grand Teton) — schematic netlist excerpt (pin names and nets, part order shuffled) for the footprints in the layout excerpt that follows; sources: Cadence DE-HDL packaged netlist, KiCad conversion of 04192023_DAF0TMB3IC0_F0TG_MB_C_brd_V02_OCP.brd

R407  Q_RES  0 5% CHIP  pkg 0402LF  page 80 : A = P12V_OCP_V3_2_PLD_PWRGD ; B = HP_LVC3_OCP_V3_2_P12V_PWRGD_R
R1930  Q_RES  10K 1% CHIP  pkg 0402LF  page 131 : A = GND ; B = OCP_SFF_MAIN_PWR_EN

(kicad_pcb
	(version 20260206)
	(generator "pcbnew")
	(generator_version "10.0")
	(general
		(thickness 1.6)
		(legacy_teardrops no)
	)
	(paper "A4")
	(title_block
		(title "04192023_DAF0TMB3IC0_F0TG_MB_C_brd_V02_OCP.brd")
		(comment 1 "Grand Teton / footprints 5756-5757 of 8354")
	)
	(layers
		(0 "F.Cu" signal "TOP")
		(4 "In1.Cu" signal "GND")
		(6 "In2.Cu" signal "IN1")
		(8 "In3.Cu" signal "GND1")
		(10 "In4.Cu" signal "IN2")
		(12 "In5.Cu" signal "GND2")
		(14 "In6.Cu" signal "IN3")
		(16 "In7.Cu" signal "GND3")
		(18 "In8.Cu" signal "VCC")
		(20 "In9.Cu" signal "VCC1")
		(22 "In10.Cu" signal "GND4")
		(24 "In11.Cu" signal "IN4")
		(26 "In12.Cu" signal "GND5")
		(28 "In13.Cu" signal "IN5")
		(30 "In14.Cu" signal "GND6")
		(32 "In15.Cu" signal "IN6")
		(34 "In16.Cu" signal "GND7")
		(2 "B.Cu" signal "BOTTOM")
		(9 "F.Adhes" user "F.Adhesive")
		(11 "B.Adhes" user "B.Adhesive")
		(13 "F.Paste" user "Package Geometry/Pastemask Top")
		(15 "B.Paste" user "Package Geometry/Pastemask Bottom")
		(5 "F.SilkS" user "Ref Des/Silkscreen Top")
		(7 "B.SilkS" user "Ref Des/Silkscreen Bottom")
		(1 "F.Mask" user "Board Geometry/Soldermask Top")
		(3 "B.Mask" user "Board Geometry/Soldermask Bottom")
		(17 "Dwgs.User" user "User.Drawings")
		(19 "Cmts.User" user "User.Comments")
		(21 "Eco1.User" user "User.Eco1")
		(23 "Eco2.User" user "User.Eco2")
		(25 "Edge.Cuts" user "Board Geometry/Outline")
		(27 "Margin" user)
		(31 "F.CrtYd" user "Package Geometry/Place Bound Top")
		(29 "B.CrtYd" user "Package Geometry/Place Bound Bottom")
		(35 "F.Fab" user "Ref Des/Assembly Top")
		(33 "B.Fab" user "Ref Des/Assembly Bottom")
	)
	(footprint ""
		(layer "B.Cu")
		(at 163.74618 -117.33022 180)
		(property "Reference" "R407"
			(at 0 0 0)
			(layer "B.SilkS")
			(hide yes)
			(effects
				(font
					(size 1.27 1.27)
				)
				(justify mirror)
			)
		)
		(property "Value" ""
			(at 0 0 0)
			(layer "B.Fab")
			(effects
				(font
					(size 1.27 1.27)
				)
				(justify mirror)
			)
		)
		(duplicate_pad_numbers_are_jumpers no)
		(fp_line
			(start 0.7874 0.4064)
			(end 0.7874 -0.4064)
			(stroke
				(width 0.1524)
				(type default)
			)
			(layer "B.SilkS")
		)
		(fp_line
			(start 0.7874 -0.4064)
			(end -0.7874 -0.4064)
			(stroke
				(width 0.1524)
				(type default)
			)
			(layer "B.SilkS")
		)
		(fp_line
			(start -0.7874 0.4064)
			(end 0.7874 0.4064)
			(stroke
				(width 0.1524)
				(type default)
			)
			(layer "B.SilkS")
		)
		(fp_line
			(start -0.7874 -0.4064)
			(end -0.7874 0.4064)
			(stroke
				(width 0.1524)
				(type default)
			)
			(layer "B.SilkS")
		)
		(fp_line
			(start 0.67945 0.3048)
			(end 0.67945 -0.305054)
			(stroke
				(width 0.1)
				(type default)
			)
			(layer "B.Fab")
		)
		(fp_line
			(start 0.67945 -0.305054)
			(end 0.12065 -0.305054)
			(stroke
				(width 0.1)
				(type default)
			)
			(layer "B.Fab")
		)
		(fp_line
			(start 0.12065 0.3048)
			(end 0.67945 0.3048)
			(stroke
				(width 0.1)
				(type default)
			)
			(layer "B.Fab")
		)
		(fp_line
			(start 0.12065 0.2794)
			(end 0.12065 0.3048)
			(stroke
				(width 0.1)
				(type default)
			)
			(layer "B.Fab")
		)
		(fp_line
			(start 0.12065 -0.2794)
			(end -0.12065 -0.2794)
			(stroke
				(width 0.1)
				(type default)
			)
			(layer "B.Fab")
		)
		(fp_line
			(start 0.12065 -0.305054)
			(end 0.12065 -0.2794)
			(stroke
				(width 0.1)
				(type default)
			)
			(layer "B.Fab")
		)
		(fp_line
			(start -0.120396 0.3048)
			(end -0.120396 0.2794)
			(stroke
				(width 0.1)
				(type default)
			)
			(layer "B.Fab")
		)
		(fp_line
			(start -0.120396 0.2794)
			(end 0.12065 0.2794)
			(stroke
				(width 0.1)
				(type default)
			)
			(layer "B.Fab")
		)
		(fp_line
			(start -0.12065 -0.2794)
			(end -0.12065 -0.3048)
			(stroke
				(width 0.1)
				(type default)
			)
			(layer "B.Fab")
		)
		(fp_line
			(start -0.12065 -0.3048)
			(end -0.67945 -0.3048)
			(stroke
				(width 0.1)
				(type default)
			)
			(layer "B.Fab")
		)
		(fp_line
			(start -0.67945 0.3048)
			(end -0.120396 0.3048)
			(stroke
				(width 0.1)
				(type default)
			)
			(layer "B.Fab")
		)
		(fp_line
			(start -0.67945 -0.3048)
			(end -0.67945 0.3048)
			(stroke
				(width 0.1)
				(type default)
			)
			(layer "B.Fab")
		)
		(pad "1" smd circle
			(at 0.40005 0)
			(size 0 0)
			(layers "B.Cu" "B.Mask" "B.Paste")
			(net "P12V_OCP_V3_2_PLD_PWRGD")
		)
		(pad "2" smd circle
			(at -0.40005 0)
			(size 0 0)
			(layers "B.Cu" "B.Mask" "B.Paste")
			(net "HP_LVC3_OCP_V3_2_P12V_PWRGD_R")
		)
	)
	(footprint ""
		(layer "B.Cu")
		(at 455.084688 -13.102844 90)
		(property "Reference" "R1930"
			(at 0 0 90)
			(layer "B.SilkS")
			(hide yes)
			(effects
				(font
					(size 1.27 1.27)
				)
				(justify mirror)
			)
		)
		(property "Value" ""
			(at 0 0 90)
			(layer "B.Fab")
			(effects
				(font
					(size 1.27 1.27)
				)
				(justify mirror)
			)
		)
		(duplicate_pad_numbers_are_jumpers no)
		(fp_line
			(start 0.7874 -0.4064)
			(end -0.7874 -0.4064)
			(stroke
				(width 0.1524)
				(type default)
			)
			(layer "B.SilkS")
		)
		(fp_line
			(start -0.7874 -0.4064)
			(end -0.7874 0.4064)
			(stroke
				(width 0.1524)
				(type default)
			)
			(layer "B.SilkS")
		)
		(fp_line
			(start 0.7874 0.4064)
			(end 0.7874 -0.4064)
			(stroke
				(width 0.1524)
				(type default)
			)
			(layer "B.SilkS")
		)
		(fp_line
			(start -0.7874 0.4064)
			(end 0.7874 0.4064)
			(stroke
				(width 0.1524)
				(type default)
			)
			(layer "B.SilkS")
		)
		(fp_line
			(start 0.67945 -0.305054)
			(end 0.12065 -0.305054)
			(stroke
				(width 0.1)
				(type default)
			)
			(layer "B.Fab")
		)
		(fp_line
			(start 0.12065 -0.305054)
			(end 0.12065 -0.2794)
			(stroke
				(width 0.1)
				(type default)
			)
			(layer "B.Fab")
		)
		(fp_line
			(start -0.12065 -0.3048)
			(end -0.67945 -0.3048)
			(stroke
				(width 0.1)
				(type default)
			)
			(layer "B.Fab")
		)
		(fp_line
			(start -0.67945 -0.3048)
			(end -0.67945 0.3048)
			(stroke
				(width 0.1)
				(type default)
			)
			(layer "B.Fab")
		)
		(fp_line
			(start 0.12065 -0.2794)
			(end -0.12065 -0.2794)
			(stroke
				(width 0.1)
				(type default)
			)
			(layer "B.Fab")
		)
		(fp_line
			(start -0.12065 -0.2794)
			(end -0.12065 -0.3048)
			(stroke
				(width 0.1)
				(type default)
			)
			(layer "B.Fab")
		)
		(fp_line
			(start 0.12065 0.2794)
			(end 0.12065 0.3048)
			(stroke
				(width 0.1)
				(type default)
			)
			(layer "B.Fab")
		)
		(fp_line
			(start -0.120396 0.2794)
			(end 0.12065 0.2794)
			(stroke
				(width 0.1)
				(type default)
			)
			(layer "B.Fab")
		)
		(fp_line
			(start 0.67945 0.3048)
			(end 0.67945 -0.305054)
			(stroke
				(width 0.1)
				(type default)
			)
			(layer "B.Fab")
		)
		(fp_line
			(start 0.12065 0.3048)
			(end 0.67945 0.3048)
			(stroke
				(width 0.1)
				(type default)
			)
			(layer "B.Fab")
		)
		(fp_line
			(start -0.120396 0.3048)
			(end -0.120396 0.2794)
			(stroke
				(width 0.1)
				(type default)
			)
			(layer "B.Fab")
		)
		(fp_line
			(start -0.67945 0.3048)
			(end -0.120396 0.3048)
			(stroke
				(width 0.1)
				(type default)
			)
			(layer "B.Fab")
		)
		(pad "1" smd circle
			(at 0.40005 0 270)
			(size 0 0)
			(layers "B.Cu" "B.Mask" "B.Paste")
			(net "GND")
		)
		(pad "2" smd circle
			(at -0.40005 0 270)
			(size 0 0)
			(layers "B.Cu" "B.Mask" "B.Paste")
			(net "OCP_SFF_MAIN_PWR_EN")
		)
	)
)
